(kicad_pcb
	(version 20260206)
	(generator "pcbnew")
	(generator_version "10.0")
	(general
		(thickness 1.6)
		(legacy_teardrops no)
	)
	(paper "A4")
	(title_block
		(title "peb — Lightning_PEB_BRD.brd")
		(comment 1 "Lightning (Wiwynn / Facebook NVMe JBOF) / footprints 1284-1290 of 2563")
	)
	(layers
		(0 "F.Cu" signal "TOP")
		(4 "In1.Cu" signal "L2GND")
		(6 "In2.Cu" signal "L3")
		(8 "In3.Cu" signal "L4VCC")
		(10 "In4.Cu" signal "L5VCC")
		(12 "In5.Cu" signal "L6")
		(14 "In6.Cu" signal "L7GND")
		(2 "B.Cu" signal "BOTTOM")
		(9 "F.Adhes" user "F.Adhesive")
		(11 "B.Adhes" user "B.Adhesive")
		(13 "F.Paste" user "Package Geometry/Pastemask Top")
		(15 "B.Paste" user "Package Geometry/Pastemask Bottom")
		(5 "F.SilkS" user "Ref Des/Silkscreen Top")
		(7 "B.SilkS" user "Ref Des/Silkscreen Bottom")
		(1 "F.Mask" user "Board Geometry/Soldermask Top")
		(3 "B.Mask" user "Board Geometry/Soldermask Bottom")
		(17 "Dwgs.User" user "User.Drawings")
		(19 "Cmts.User" user "User.Comments")
		(21 "Eco1.User" user "User.Eco1")
		(23 "Eco2.User" user "User.Eco2")
		(25 "Edge.Cuts" user "Board Geometry/Outline")
		(27 "Margin" user)
		(31 "F.CrtYd" user "Package Geometry/Place Bound Top")
		(29 "B.CrtYd" user "Package Geometry/Place Bound Bottom")
		(35 "F.Fab" user "Ref Des/Assembly Top")
		(33 "B.Fab" user "Ref Des/Assembly Bottom")
	)
	(footprint ""
		(layer "F.Cu")
		(at 261.239 -17.272 180)
		(property "Reference" "PC222"
			(at 0 0 180)
			(layer "F.SilkS")
			(hide yes)
			(effects
				(font
					(size 1.27 1.27)
				)
			)
		)
		(property "Value" "SC1U16V3KX-5GP"
			(at 0 -2.8194 180)
			(unlocked yes)
			(layer "F.Fab")
			(hide yes)
			(effects
				(font
					(size 1.016 1.016)
					(thickness 0.1524)
				)
			)
		)
		(property "Device Type" "C603H36"
			(at 0 -4.3434 180)
			(unlocked yes)
			(layer "F.Fab")
			(hide yes)
			(effects
				(font
					(size 1.016 1.016)
					(thickness 0.1524)
				)
			)
		)
		(duplicate_pad_numbers_are_jumpers no)
		(fp_line
			(start 0.508 0)
			(end -0.508 0)
			(stroke
				(width 0.2032)
				(type default)
			)
			(layer "F.SilkS")
		)
		(fp_rect
			(start -0.5842 1.3335)
			(end 0.5842 -1.3335)
			(stroke
				(width 0)
				(type default)
			)
			(fill no)
			(layer "F.CrtYd")
		)
		(fp_rect
			(start -0.5842 1.3335)
			(end 0.5842 -1.3335)
			(stroke
				(width 0)
				(type default)
			)
			(fill no)
			(layer "F.Fab")
		)
		(pad "1" smd custom
			(at 0 -0.762 180)
			(size 0.2159 0.2159)
			(layers "F.Cu" "F.Mask" "F.Paste")
			(net "P3V3_STBY")
			(options
				(clearance outline)
				(anchor circle)
			)
			(primitives
				(gr_poly
					(pts
						(arc
							(start -0.3302 -0.4318)
							(mid -0.402042 -0.402042)
							(end -0.4318 -0.3302)
						)
						(arc
							(start -0.4318 0.3302)
							(mid -0.402042 0.402042)
							(end -0.3302 0.4318)
						)
						(arc
							(start 0.3302 0.4318)
							(mid 0.402042 0.402042)
							(end 0.4318 0.3302)
						)
						(arc
							(start 0.4318 -0.3302)
							(mid 0.402042 -0.402042)
							(end 0.3302 -0.4318)
						)
					)
					(width 0)
					(fill yes)
				)
			)
		)
		(pad "2" smd custom
			(at 0 0.762 180)
			(size 0.2159 0.2159)
			(layers "F.Cu" "F.Mask" "F.Paste")
			(net "Q3203_G")
			(options
				(clearance outline)
				(anchor circle)
			)
			(primitives
				(gr_poly
					(pts
						(arc
							(start -0.3302 -0.4318)
							(mid -0.402042 -0.402042)
							(end -0.4318 -0.3302)
						)
						(arc
							(start -0.4318 0.3302)
							(mid -0.402042 0.402042)
							(end -0.3302 0.4318)
						)
						(arc
							(start 0.3302 0.4318)
							(mid 0.402042 0.402042)
							(end 0.4318 0.3302)
						)
						(arc
							(start 0.4318 -0.3302)
							(mid 0.402042 -0.402042)
							(end 0.3302 -0.4318)
						)
					)
					(width 0)
					(fill yes)
				)
			)
		)
	)
	(footprint ""
		(layer "F.Cu")
		(at 219.456 -2.032 90)
		(property "Reference" "R435"
			(at 0 0 90)
			(layer "F.SilkS")
			(hide yes)
			(effects
				(font
					(size 1.27 1.27)
				)
			)
		)
		(property "Value" "0R2J-2-GP"
			(at 0.064008 -3.993896 90)
			(unlocked yes)
			(layer "F.Fab")
			(hide yes)
			(effects
				(font
					(size 1.016 1.016)
					(thickness 0.1524)
				)
			)
		)
		(property "Device Type" "R402H16"
			(at 0.064008 -5.517896 90)
			(unlocked yes)
			(layer "F.Fab")
			(hide yes)
			(effects
				(font
					(size 1.016 1.016)
					(thickness 0.1524)
				)
			)
		)
		(duplicate_pad_numbers_are_jumpers no)
		(fp_line
			(start 0.508 -0.9398)
			(end -0.508 -0.9398)
			(stroke
				(width 0.1524)
				(type default)
			)
			(layer "F.SilkS")
		)
		(fp_line
			(start -0.508 -0.9398)
			(end -0.508 0.9398)
			(stroke
				(width 0.1524)
				(type default)
			)
			(layer "F.SilkS")
		)
		(fp_rect
			(start -0.508 0.9398)
			(end 0.508 -0.9398)
			(stroke
				(width 0)
				(type default)
			)
			(fill no)
			(layer "F.CrtYd")
		)
		(fp_rect
			(start -0.508 0.9398)
			(end 0.508 -0.9398)
			(stroke
				(width 0)
				(type default)
			)
			(fill no)
			(layer "F.Fab")
		)
		(pad "1" smd custom
			(at 0 -0.4445 90)
			(size 0.1397 0.1397)
			(layers "F.Cu" "F.Mask" "F.Paste")
			(net "EXP_SMART_TX")
			(options
				(clearance outline)
				(anchor circle)
			)
			(primitives
				(gr_poly
					(pts
						(arc
							(start -0.1778 -0.2794)
							(mid -0.249642 -0.249642)
							(end -0.2794 -0.1778)
						)
						(arc
							(start -0.2794 0.1778)
							(mid -0.249642 0.249642)
							(end -0.1778 0.2794)
						)
						(arc
							(start 0.1778 0.2794)
							(mid 0.249642 0.249642)
							(end 0.2794 0.1778)
						)
						(arc
							(start 0.2794 -0.1778)
							(mid 0.249642 -0.249642)
							(end 0.1778 -0.2794)
						)
					)
					(width 0)
					(fill yes)
				)
			)
		)
		(pad "2" smd custom
			(at 0 0.4445 90)
			(size 0.1397 0.1397)
			(layers "F.Cu" "F.Mask" "F.Paste")
			(net "EXP_UART_TX_R")
			(options
				(clearance outline)
				(anchor circle)
			)
			(primitives
				(gr_poly
					(pts
						(arc
							(start -0.1778 -0.2794)
							(mid -0.249642 -0.249642)
							(end -0.2794 -0.1778)
						)
						(arc
							(start -0.2794 0.1778)
							(mid -0.249642 0.249642)
							(end -0.1778 0.2794)
						)
						(arc
							(start 0.1778 0.2794)
							(mid 0.249642 0.249642)
							(end 0.2794 0.1778)
						)
						(arc
							(start 0.2794 -0.1778)
							(mid 0.249642 -0.249642)
							(end 0.1778 -0.2794)
						)
					)
					(width 0)
					(fill yes)
				)
			)
		)
	)
	(footprint ""
		(layer "F.Cu")
		(at 33.782 -116.713)
		(property "Reference" "R20"
			(at 0 0 0)
			(layer "F.SilkS")
			(hide yes)
			(effects
				(font
					(size 1.27 1.27)
				)
			)
		)
		(property "Value" "100R2F-L1-GP-U"
			(at 0.064008 -3.993896 0)
			(unlocked yes)
			(layer "F.Fab")
			(hide yes)
			(effects
				(font
					(size 1.016 1.016)
					(thickness 0.1524)
				)
			)
		)
		(property "Device Type" "R402H14"
			(at 0.064008 -5.517896 0)
			(unlocked yes)
			(layer "F.Fab")
			(hide yes)
			(effects
				(font
					(size 1.016 1.016)
					(thickness 0.1524)
				)
			)
		)
		(duplicate_pad_numbers_are_jumpers no)
		(fp_line
			(start -0.508 -0.9398)
			(end -0.508 0.9398)
			(stroke
				(width 0.1524)
				(type default)
			)
			(layer "F.SilkS")
		)
		(fp_line
			(start 0.508 -0.9398)
			(end -0.508 -0.9398)
			(stroke
				(width 0.1524)
				(type default)
			)
			(layer "F.SilkS")
		)
		(fp_rect
			(start -0.508 0.9398)
			(end 0.508 -0.9398)
			(stroke
				(width 0)
				(type default)
			)
			(fill no)
			(layer "F.CrtYd")
		)
		(fp_rect
			(start -0.508 0.9398)
			(end 0.508 -0.9398)
			(stroke
				(width 0)
				(type default)
			)
			(fill no)
			(layer "F.Fab")
		)
		(pad "1" smd custom
			(at 0 -0.4445)
			(size 0.1397 0.1397)
			(layers "F.Cu" "F.Mask" "F.Paste")
			(net "PMC_PLX_BOARD")
			(options
				(clearance outline)
				(anchor circle)
			)
			(primitives
				(gr_poly
					(pts
						(arc
							(start -0.1778 -0.2794)
							(mid -0.249642 -0.249642)
							(end -0.2794 -0.1778)
						)
						(arc
							(start -0.2794 0.1778)
							(mid -0.249642 0.249642)
							(end -0.1778 0.2794)
						)
						(arc
							(start 0.1778 0.2794)
							(mid 0.249642 0.249642)
							(end 0.2794 0.1778)
						)
						(arc
							(start 0.2794 -0.1778)
							(mid 0.249642 -0.249642)
							(end 0.1778 -0.2794)
						)
					)
					(width 0)
					(fill yes)
				)
			)
		)
		(pad "2" smd custom
			(at 0 0.4445)
			(size 0.1397 0.1397)
			(layers "F.Cu" "F.Mask" "F.Paste")
			(net "GND")
			(options
				(clearance outline)
				(anchor circle)
			)
			(primitives
				(gr_poly
					(pts
						(arc
							(start -0.1778 -0.2794)
							(mid -0.249642 -0.249642)
							(end -0.2794 -0.1778)
						)
						(arc
							(start -0.2794 0.1778)
							(mid -0.249642 0.249642)
							(end -0.1778 0.2794)
						)
						(arc
							(start 0.1778 0.2794)
							(mid 0.249642 0.249642)
							(end 0.2794 0.1778)
						)
						(arc
							(start 0.2794 -0.1778)
							(mid 0.249642 -0.249642)
							(end 0.1778 -0.2794)
						)
					)
					(width 0)
					(fill yes)
				)
			)
		)
	)
	(footprint ""
		(layer "F.Cu")
		(at 175.4886 -53.8988 -90)
		(property "Reference" "R608"
			(at 0 0 270)
			(layer "F.SilkS")
			(hide yes)
			(effects
				(font
					(size 1.27 1.27)
				)
			)
		)
		(property "Value" "0R2J-2-GP"
			(at 0.064008 -3.993896 270)
			(unlocked yes)
			(layer "F.Fab")
			(hide yes)
			(effects
				(font
					(size 1.016 1.016)
					(thickness 0.1524)
				)
			)
		)
		(property "Device Type" "R402H16"
			(at 0.064008 -5.517896 270)
			(unlocked yes)
			(layer "F.Fab")
			(hide yes)
			(effects
				(font
					(size 1.016 1.016)
					(thickness 0.1524)
				)
			)
		)
		(duplicate_pad_numbers_are_jumpers no)
		(fp_line
			(start -0.508 -0.9398)
			(end -0.508 0.9398)
			(stroke
				(width 0.1524)
				(type default)
			)
			(layer "F.SilkS")
		)
		(fp_line
			(start 0.508 -0.9398)
			(end -0.508 -0.9398)
			(stroke
				(width 0.1524)
				(type default)
			)
			(layer "F.SilkS")
		)
		(fp_rect
			(start -0.508 0.9398)
			(end 0.508 -0.9398)
			(stroke
				(width 0)
				(type default)
			)
			(fill no)
			(layer "F.CrtYd")
		)
		(fp_rect
			(start -0.508 0.9398)
			(end 0.508 -0.9398)
			(stroke
				(width 0)
				(type default)
			)
			(fill no)
			(layer "F.Fab")
		)
		(pad "1" smd custom
			(at 0 -0.4445 270)
			(size 0.1397 0.1397)
			(layers "F.Cu" "F.Mask" "F.Paste")
			(net "VS3_LED_R")
			(options
				(clearance outline)
				(anchor circle)
			)
			(primitives
				(gr_poly
					(pts
						(arc
							(start -0.1778 -0.2794)
							(mid -0.249642 -0.249642)
							(end -0.2794 -0.1778)
						)
						(arc
							(start -0.2794 0.1778)
							(mid -0.249642 0.249642)
							(end -0.1778 0.2794)
						)
						(arc
							(start 0.1778 0.2794)
							(mid 0.249642 0.249642)
							(end 0.2794 0.1778)
						)
						(arc
							(start 0.2794 -0.1778)
							(mid 0.249642 -0.249642)
							(end 0.1778 -0.2794)
						)
					)
					(width 0)
					(fill yes)
				)
			)
		)
		(pad "2" smd custom
			(at 0 0.4445 270)
			(size 0.1397 0.1397)
			(layers "F.Cu" "F.Mask" "F.Paste")
			(net "VS3_LED")
			(options
				(clearance outline)
				(anchor circle)
			)
			(primitives
				(gr_poly
					(pts
						(arc
							(start -0.1778 -0.2794)
							(mid -0.249642 -0.249642)
							(end -0.2794 -0.1778)
						)
						(arc
							(start -0.2794 0.1778)
							(mid -0.249642 0.249642)
							(end -0.1778 0.2794)
						)
						(arc
							(start 0.1778 0.2794)
							(mid 0.249642 0.249642)
							(end 0.2794 0.1778)
						)
						(arc
							(start 0.2794 -0.1778)
							(mid 0.249642 -0.249642)
							(end 0.1778 -0.2794)
						)
					)
					(width 0)
					(fill yes)
				)
			)
		)
	)
	(footprint ""
		(layer "F.Cu")
		(at 36.842954 -164.702744 90)
		(property "Reference" "C180"
			(at 0 0 90)
			(layer "F.SilkS")
			(hide yes)
			(effects
				(font
					(size 1.27 1.27)
				)
			)
		)
		(property "Value" "SC1U10V2KX-4-GP"
			(at 1.1811 -2.7051 90)
			(unlocked yes)
			(layer "F.Fab")
			(hide yes)
			(effects
				(font
					(size 1.016 1.016)
					(thickness 0.1524)
				)
			)
		)
		(property "Device Type" "C402H22"
			(at 1.1811 -4.2291 90)
			(unlocked yes)
			(layer "F.Fab")
			(hide yes)
			(effects
				(font
					(size 1.016 1.016)
					(thickness 0.1524)
				)
			)
		)
		(duplicate_pad_numbers_are_jumpers no)
		(fp_rect
			(start -0.4318 0.9525)
			(end 0.4318 -0.9525)
			(stroke
				(width 0)
				(type default)
			)
			(fill no)
			(layer "F.CrtYd")
		)
		(fp_rect
			(start -0.4318 0.9525)
			(end 0.4318 -0.9525)
			(stroke
				(width 0)
				(type default)
			)
			(fill no)
			(layer "F.Fab")
		)
		(pad "1" smd custom
			(at 0 -0.4445 90)
			(size 0.1524 0.1524)
			(layers "F.Cu" "F.Mask" "F.Paste")
			(net "DDR_VREF")
			(options
				(clearance outline)
				(anchor circle)
			)
			(primitives
				(gr_poly
					(pts
						(arc
							(start 0.3048 -0.2032)
							(mid 0.275042 -0.275042)
							(end 0.2032 -0.3048)
						)
						(arc
							(start -0.2032 -0.3048)
							(mid -0.275042 -0.275042)
							(end -0.3048 -0.2032)
						)
						(arc
							(start -0.3048 0.2032)
							(mid -0.275042 0.275042)
							(end -0.2032 0.3048)
						)
						(arc
							(start 0.2032 0.3048)
							(mid 0.275042 0.275042)
							(end 0.3048 0.2032)
						)
					)
					(width 0)
					(fill yes)
				)
			)
		)
		(pad "2" smd custom
			(at 0 0.4445 90)
			(size 0.1524 0.1524)
			(layers "F.Cu" "F.Mask" "F.Paste")
			(net "GND")
			(options
				(clearance outline)
				(anchor circle)
			)
			(primitives
				(gr_poly
					(pts
						(arc
							(start 0.3048 -0.2032)
							(mid 0.275042 -0.275042)
							(end 0.2032 -0.3048)
						)
						(arc
							(start -0.2032 -0.3048)
							(mid -0.275042 -0.275042)
							(end -0.3048 -0.2032)
						)
						(arc
							(start -0.3048 0.2032)
							(mid -0.275042 0.275042)
							(end -0.2032 0.3048)
						)
						(arc
							(start 0.2032 0.3048)
							(mid 0.275042 0.275042)
							(end 0.3048 0.2032)
						)
					)
					(width 0)
					(fill yes)
				)
			)
		)
	)
	(footprint ""
		(layer "F.Cu")
		(at 340.995 -60.96 -90)
		(property "Reference" "PC175"
			(at 0 0 270)
			(layer "F.SilkS")
			(hide yes)
			(effects
				(font
					(size 1.27 1.27)
				)
			)
		)
		(property "Value" "SC10U25V5KX-GP"
			(at -0.0762 -6.1214 270)
			(unlocked yes)
			(layer "F.Fab")
			(hide yes)
			(effects
				(font
					(size 1.016 1.016)
					(thickness 0.1524)
				)
			)
		)
		(property "Device Type" "C805H56"
			(at -0.0762 -8.1534 270)
			(unlocked yes)
			(layer "F.Fab")
			(hide yes)
			(effects
				(font
					(size 1.016 1.016)
					(thickness 0.1524)
				)
			)
		)
		(duplicate_pad_numbers_are_jumpers no)
		(fp_line
			(start 0.635 0)
			(end -0.635 0)
			(stroke
				(width 0.508)
				(type default)
			)
			(layer "F.SilkS")
		)
		(fp_rect
			(start -0.9652 1.778)
			(end 0.9652 -1.778)
			(stroke
				(width 0)
				(type default)
			)
			(fill no)
			(layer "F.CrtYd")
		)
		(fp_poly
			(pts
				(xy -0.9652 -1.778) (xy 0.9652 -1.778) (xy 0.9652 1.778) (xy -0.9652 1.778)
			)
			(stroke
				(width 0)
				(type default)
			)
			(fill no)
			(layer "F.Fab")
		)
		(pad "1" smd rect
			(at 0 -0.9652 270)
			(size 1.397 1.143)
			(layers "F.Cu" "F.Mask" "F.Paste")
			(net "P0V9_E_VIN")
		)
		(pad "2" smd rect
			(at 0 0.9652 270)
			(size 1.397 1.143)
			(layers "F.Cu" "F.Mask" "F.Paste")
			(net "GND")
		)
	)
	(footprint ""
		(layer "F.Cu")
		(at 81.364836 -67.109594 180)
		(property "Reference" "U36"
			(at 0 0 180)
			(layer "F.SilkS")
			(hide yes)
			(effects
				(font
					(size 1.27 1.27)
				)
			)
		)
		(property "Value" "MX25L25635FMI-10G-GP"
			(at 0 -14.6812 180)
			(unlocked yes)
			(layer "F.Fab")
			(hide yes)
			(effects
				(font
					(size 1.016 1.016)
					(thickness 0.1524)
				)
			)
		)
		(property "Device Type" "SOIC16-6H105"
			(at 0 -16.2052 180)
			(unlocked yes)
			(layer "F.Fab")
			(hide yes)
			(effects
				(font
					(size 1.016 1.016)
					(thickness 0.1524)
				)
			)
		)
		(duplicate_pad_numbers_are_jumpers no)
		(fp_line
			(start 4.7498 3.2258)
			(end -5.588 3.2258)
			(stroke
				(width 0.1524)
				(type default)
			)
			(layer "F.SilkS")
		)
		(fp_line
			(start 4.7498 -3.2258)
			(end 4.7498 3.2258)
			(stroke
				(width 0.1524)
				(type default)
			)
			(layer "F.SilkS")
		)
		(fp_line
			(start -5.08762 0)
			(end -5.588 0.50038)
			(stroke
				(width 0.1524)
				(type default)
			)
			(layer "F.SilkS")
		)
		(fp_line
			(start -5.4102 3.2258)
			(end -5.4102 5.7912)
			(stroke
				(width 0.508)
				(type default)
			)
			(layer "F.SilkS")
		)
		(fp_line
			(start -5.588 3.2258)
			(end -5.588 -3.2258)
			(stroke
				(width 0.1524)
				(type default)
			)
			(layer "F.SilkS")
		)
		(fp_line
			(start -5.588 -0.50038)
			(end -5.08762 0)
			(stroke
				(width 0.1524)
				(type default)
			)
			(layer "F.SilkS")
		)
		(fp_line
			(start -5.588 -3.2258)
			(end 4.7498 -3.2258)
			(stroke
				(width 0.1524)
				(type default)
			)
			(layer "F.SilkS")
		)
		(fp_poly
			(pts
				(xy -4.764786 -3.2258) (xy 4.7625 -3.2258) (xy 4.7625 3.2258) (xy -4.764786 3.2258)
			)
			(stroke
				(width 0)
				(type default)
			)
			(fill yes)
			(layer "F.SilkS")
		)
		(fp_poly
			(pts
				(xy -5.6642 6.0452) (xy 5.6642 6.0452) (xy 5.6642 -6.0452) (xy -5.6642 -6.0452)
			)
			(stroke
				(width 0)
				(type default)
			)
			(fill no)
			(layer "F.CrtYd")
		)
		(fp_poly
			(pts
				(xy -5.6642 -6.0452) (xy 5.6642 -6.0452) (xy 5.6642 6.0452) (xy -5.6642 6.0452)
			)
			(stroke
				(width 0)
				(type default)
			)
			(fill no)
			(layer "F.Fab")
		)
		(pad "1" smd rect
			(at -4.445 4.71805 180)
			(size 0.635 1.651)
			(layers "F.Cu" "F.Mask" "F.Paste")
			(net "SEC_SPI_HOLD_N")
		)
		(pad "2" smd rect
			(at -3.175 4.71805 180)
			(size 0.635 1.651)
			(layers "F.Cu" "F.Mask" "F.Paste")
			(net "P3V3_STBY")
		)
		(pad "3" smd rect
			(at -1.905 4.71805 180)
			(size 0.635 1.651)
			(layers "F.Cu" "F.Mask" "F.Paste")
			(net "SEC_RST_N_R")
		)
		(pad "4" smd rect
			(at -0.635 4.71805 180)
			(size 0.635 1.651)
			(layers "F.Cu" "F.Mask" "F.Paste")
			(net "Net_25")
		)
		(pad "5" smd rect
			(at 0.635 4.71805 180)
			(size 0.635 1.651)
			(layers "F.Cu" "F.Mask" "F.Paste")
			(net "Net_24")
		)
		(pad "6" smd rect
			(at 1.905 4.71805 180)
			(size 0.635 1.651)
			(layers "F.Cu" "F.Mask" "F.Paste")
			(net "Net_23")
		)
		(pad "7" smd rect
			(at 3.175 4.71805 180)
			(size 0.635 1.651)
			(layers "F.Cu" "F.Mask" "F.Paste")
			(net "FLA_CS_R")
		)
		(pad "8" smd rect
			(at 4.445 4.71805 180)
			(size 0.635 1.651)
			(layers "F.Cu" "F.Mask" "F.Paste")
			(net "ROMD2_SEC")
		)
		(pad "9" smd rect
			(at 4.445 -4.71805 180)
			(size 0.635 1.651)
			(layers "F.Cu" "F.Mask" "F.Paste")
			(net "FLA1_WPN")
		)
		(pad "10" smd rect
			(at 3.175 -4.71805 180)
			(size 0.635 1.651)
			(layers "F.Cu" "F.Mask" "F.Paste")
			(net "GND")
		)
		(pad "11" smd rect
			(at 1.905 -4.71805 180)
			(size 0.635 1.651)
			(layers "F.Cu" "F.Mask" "F.Paste")
			(net "Net_22")
		)
		(pad "12" smd rect
			(at 0.635 -4.71805 180)
			(size 0.635 1.651)
			(layers "F.Cu" "F.Mask" "F.Paste")
			(net "Net_21")
		)
		(pad "13" smd rect
			(at -0.635 -4.71805 180)
			(size 0.635 1.651)
			(layers "F.Cu" "F.Mask" "F.Paste")
			(net "Net_20")
		)
		(pad "14" smd rect
			(at -1.905 -4.71805 180)
			(size 0.635 1.651)
			(layers "F.Cu" "F.Mask" "F.Paste")
			(net "Net_19")
		)
		(pad "15" smd rect
			(at -3.175 -4.71805 180)
			(size 0.635 1.651)
			(layers "F.Cu" "F.Mask" "F.Paste")
			(net "ROMD1_R")
		)
		(pad "16" smd rect
			(at -4.445 -4.71805 180)
			(size 0.635 1.651)
			(layers "F.Cu" "F.Mask" "F.Paste")
			(net "ROMD0_R")
		)
	)
)
